(kicad_pcb
	(version 20241229)
	(generator "pcbnew")
	(generator_version "9.0")
	(general
		(thickness 1.61)
		(legacy_teardrops no)
	)
	(paper "A3")
	(title_block
		(title "RDIMM DDR5 Tester")
		(date "2026-05-21")
		(rev "2.2.0")
		(company "Antmicro")
		(comment 9 "footprints 272-276 of 796")
	)
	(layers
		(0 "F.Cu" signal)
		(4 "In1.Cu" power)
		(6 "In2.Cu" mixed)
		(8 "In3.Cu" power)
		(10 "In4.Cu" mixed)
		(12 "In5.Cu" power)
		(14 "In6.Cu" mixed)
		(16 "In7.Cu" power)
		(18 "In8.Cu" power)
		(20 "In9.Cu" mixed)
		(22 "In10.Cu" power)
		(2 "B.Cu" signal)
		(9 "F.Adhes" user "F.Adhesive")
		(11 "B.Adhes" user "B.Adhesive")
		(13 "F.Paste" user)
		(15 "B.Paste" user)
		(5 "F.SilkS" user "F.Silkscreen")
		(7 "B.SilkS" user "B.Silkscreen")
		(1 "F.Mask" user)
		(3 "B.Mask" user)
		(17 "Dwgs.User" user "User.Drawings")
		(19 "Cmts.User" user "User.Comments")
		(21 "Eco1.User" user "User.Eco1")
		(23 "Eco2.User" user "User.Eco2")
		(25 "Edge.Cuts" user)
		(27 "Margin" user)
		(31 "F.CrtYd" user "F.Courtyard")
		(29 "B.CrtYd" user "B.Courtyard")
		(35 "F.Fab" user)
		(33 "B.Fab" user)
	)
	(footprint "antmicro-footprints:C_0402_1005Metric"
		(layer "F.Cu")
		(at 152.73 193.5 180)
		(descr "Capacitor SMD 0402")
		(tags "capacitor SMD 0402")
		(property "Reference" "C176"
			(at -3.82 -0.45 0)
			(layer "F.SilkS")
			(effects
				(font
					(size 0.7 0.7)
					(thickness 0.15)
				)
				(justify right bottom)
			)
		)
		(property "Value" "C_100n_0402"
			(at -1.022927 2.155213 0)
			(layer "F.Fab")
			(effects
				(font
					(size 0.7 0.7)
					(thickness 0.15)
				)
				(justify right bottom)
			)
		)
		(property "Datasheet" "https://www.murata.com/products/productdetail?partno=GRM155R61H104KE14%23"
			(at 0 0 180)
			(layer "F.Fab")
			(hide yes)
			(effects
				(font
					(size 1.27 1.27)
					(thickness 0.15)
				)
			)
		)
		(property "Manufacturer" "Murata"
			(at 0 0 180)
			(unlocked yes)
			(layer "F.Fab")
			(hide yes)
			(effects
				(font
					(size 1 1)
					(thickness 0.15)
				)
			)
		)
		(property "MPN" "GRM155R61H104KE14D"
			(at 0 0 180)
			(unlocked yes)
			(layer "F.Fab")
			(hide yes)
			(effects
				(font
					(size 1 1)
					(thickness 0.15)
				)
			)
		)
		(property "Val" "100n"
			(at 0 0 180)
			(unlocked yes)
			(layer "F.Fab")
			(hide yes)
			(effects
				(font
					(size 1 1)
					(thickness 0.15)
				)
			)
		)
		(property "License" "Apache-2.0"
			(at 0 0 180)
			(unlocked yes)
			(layer "F.Fab")
			(hide yes)
			(effects
				(font
					(size 1 1)
					(thickness 0.15)
				)
			)
		)
		(property "Author" "Antmicro"
			(at 0 0 180)
			(unlocked yes)
			(layer "F.Fab")
			(hide yes)
			(effects
				(font
					(size 1 1)
					(thickness 0.15)
				)
			)
		)
		(property "Voltage" "50V"
			(at 0 0 180)
			(unlocked yes)
			(layer "F.Fab")
			(hide yes)
			(effects
				(font
					(size 1 1)
					(thickness 0.15)
				)
			)
		)
		(property "Dielectric" "X5R"
			(at 0 0 180)
			(unlocked yes)
			(layer "F.Fab")
			(hide yes)
			(effects
				(font
					(size 1 1)
					(thickness 0.15)
				)
			)
		)
		(sheetname "/Supply/")
		(sheetfile "supply.kicad_sch")
		(attr smd)
		(fp_rect
			(start -0.925 -0.47)
			(end 0.925 0.47)
			(stroke
				(width 0.05)
				(type default)
			)
			(fill no)
			(layer "F.CrtYd")
		)
		(fp_line
			(start 0.504 0.248)
			(end -0.494 0.248)
			(stroke
				(width 0.15)
				(type solid)
			)
			(layer "F.Fab")
		)
		(fp_line
			(start 0.504 -0.25)
			(end 0.504 0.248)
			(stroke
				(width 0.15)
				(type solid)
			)
			(layer "F.Fab")
		)
		(fp_line
			(start -0.494 0.248)
			(end -0.494 -0.25)
			(stroke
				(width 0.15)
				(type solid)
			)
			(layer "F.Fab")
		)
		(fp_line
			(start -0.494 -0.25)
			(end 0.504 -0.25)
			(stroke
				(width 0.15)
				(type solid)
			)
			(layer "F.Fab")
		)
		(fp_text user "License: Apache-2.0"
			(at -0.939 5.799 180)
			(layer "F.Fab")
			(effects
				(font
					(size 0.7 0.7)
					(thickness 0.15)
				)
				(justify left bottom)
			)
		)
		(fp_text user "${REFERENCE}"
			(at -0.939 4.599 180)
			(layer "F.Fab")
			(effects
				(font
					(size 0.7 0.7)
					(thickness 0.15)
				)
				(justify left bottom)
			)
		)
		(fp_text user "Author: Antmicro"
			(at -0.939 3.399 180)
			(layer "F.Fab")
			(effects
				(font
					(size 0.7 0.7)
					(thickness 0.15)
				)
				(justify left bottom)
			)
		)
		(pad "1" smd roundrect
			(at -0.48 0 180)
			(size 0.59 0.64)
			(layers "F.Cu" "F.Mask" "F.Paste")
			(roundrect_rratio 0.25)
			(net 1 "GND")
			(pintype "passive")
		)
		(pad "2" smd roundrect
			(at 0.48 0 180)
			(size 0.59 0.64)
			(layers "F.Cu" "F.Mask" "F.Paste")
			(roundrect_rratio 0.25)
			(net 324 "/Supply/12V_PCIE_fused")
			(pintype "passive")
		)
	)
	(footprint "antmicro-footprints:C_0402_1005Metric"
		(layer "F.Cu")
		(at 215.659999 179.205 180)
		(descr "Capacitor SMD 0402")
		(tags "capacitor SMD 0402")
		(property "Reference" "C217"
			(at 0.929999 -0.455 0)
			(layer "F.SilkS")
			(effects
				(font
					(size 0.7 0.7)
					(thickness 0.15)
				)
				(justify right bottom)
			)
		)
		(property "Value" "C_4u7_25V_0402"
			(at -1.022927 2.155213 0)
			(layer "F.Fab")
			(effects
				(font
					(size 0.7 0.7)
					(thickness 0.15)
				)
				(justify right bottom)
			)
		)
		(property "Datasheet" "https://www.murata.com/products/productdetail?partno=GRM155C61E475ME15%23"
			(at 0 0 180)
			(layer "F.Fab")
			(hide yes)
			(effects
				(font
					(size 1.27 1.27)
					(thickness 0.15)
				)
			)
		)
		(property "MPN" "GRM155C61E475ME15J"
			(at 0 0 180)
			(unlocked yes)
			(layer "F.Fab")
			(hide yes)
			(effects
				(font
					(size 1 1)
					(thickness 0.15)
				)
			)
		)
		(property "Manufacturer" "Murata"
			(at 0 0 180)
			(unlocked yes)
			(layer "F.Fab")
			(hide yes)
			(effects
				(font
					(size 1 1)
					(thickness 0.15)
				)
			)
		)
		(property "License" "Apache-2.0"
			(at 0 0 180)
			(unlocked yes)
			(layer "F.Fab")
			(hide yes)
			(effects
				(font
					(size 1 1)
					(thickness 0.15)
				)
			)
		)
		(property "Author" "Antmicro"
			(at 0 0 180)
			(unlocked yes)
			(layer "F.Fab")
			(hide yes)
			(effects
				(font
					(size 1 1)
					(thickness 0.15)
				)
			)
		)
		(property "Val" "4u7"
			(at 0 0 180)
			(unlocked yes)
			(layer "F.Fab")
			(hide yes)
			(effects
				(font
					(size 1 1)
					(thickness 0.15)
				)
			)
		)
		(property "Voltage" "25V"
			(at 0 0 180)
			(unlocked yes)
			(layer "F.Fab")
			(hide yes)
			(effects
				(font
					(size 1 1)
					(thickness 0.15)
				)
			)
		)
		(property "Dielectric" "X5S"
			(at 0 0 180)
			(unlocked yes)
			(layer "F.Fab")
			(hide yes)
			(effects
				(font
					(size 1 1)
					(thickness 0.15)
				)
			)
		)
		(sheetname "/Supply/DC-DC VCCINT/")
		(sheetfile "dc-dc-vccint.kicad_sch")
		(attr smd)
		(fp_rect
			(start -0.925 -0.47)
			(end 0.925 0.47)
			(stroke
				(width 0.05)
				(type default)
			)
			(fill no)
			(layer "F.CrtYd")
		)
		(fp_line
			(start 0.504 0.248)
			(end -0.494 0.248)
			(stroke
				(width 0.15)
				(type solid)
			)
			(layer "F.Fab")
		)
		(fp_line
			(start 0.504 -0.25)
			(end 0.504 0.248)
			(stroke
				(width 0.15)
				(type solid)
			)
			(layer "F.Fab")
		)
		(fp_line
			(start -0.494 0.248)
			(end -0.494 -0.25)
			(stroke
				(width 0.15)
				(type solid)
			)
			(layer "F.Fab")
		)
		(fp_line
			(start -0.494 -0.25)
			(end 0.504 -0.25)
			(stroke
				(width 0.15)
				(type solid)
			)
			(layer "F.Fab")
		)
		(fp_text user "Author: Antmicro"
			(at -0.939 3.399 180)
			(layer "F.Fab")
			(effects
				(font
					(size 0.7 0.7)
					(thickness 0.15)
				)
				(justify left bottom)
			)
		)
		(fp_text user "${REFERENCE}"
			(at -0.939 4.599 180)
			(layer "F.Fab")
			(effects
				(font
					(size 0.7 0.7)
					(thickness 0.15)
				)
				(justify left bottom)
			)
		)
		(fp_text user "License: Apache-2.0"
			(at -0.939 5.799 180)
			(layer "F.Fab")
			(effects
				(font
					(size 0.7 0.7)
					(thickness 0.15)
				)
				(justify left bottom)
			)
		)
		(pad "1" smd roundrect
			(at -0.48 0 180)
			(size 0.59 0.64)
			(layers "F.Cu" "F.Mask" "F.Paste")
			(roundrect_rratio 0.25)
			(net 1 "GND")
			(pintype "passive")
		)
		(pad "2" smd roundrect
			(at 0.48 0 180)
			(size 0.59 0.64)
			(layers "F.Cu" "F.Mask" "F.Paste")
			(roundrect_rratio 0.25)
			(net 222 "Net-(U4-V_{DRV})")
			(pintype "passive")
		)
	)
	(footprint "antmicro-footprints:R_0402_1005Metric"
		(layer "F.Cu")
		(at 108.824499 141.649 180)
		(descr "Resistor SMD 0402")
		(tags "resistor SMD 0402")
		(property "Reference" "R68"
			(at -3.175501 -0.626 0)
			(layer "F.SilkS")
			(effects
				(font
					(size 0.7 0.7)
					(thickness 0.15)
				)
				(justify right bottom)
			)
		)
		(property "Value" "R_5k11_0402"
			(at -1.011843 1.772047 0)
			(layer "F.Fab")
			(effects
				(font
					(size 0.7 0.7)
					(thickness 0.15)
				)
				(justify right bottom)
			)
		)
		(property "Datasheet" "https://www.bourns.com/docs/product-datasheets/cr.pdf"
			(at 0 0 180)
			(layer "F.Fab")
			(hide yes)
			(effects
				(font
					(size 1.27 1.27)
					(thickness 0.15)
				)
			)
		)
		(property "Manufacturer" "Bourns"
			(at 0 0 180)
			(unlocked yes)
			(layer "F.Fab")
			(hide yes)
			(effects
				(font
					(size 1 1)
					(thickness 0.15)
				)
			)
		)
		(property "MPN" "CR0402-FX-5111GLF"
			(at 0 0 180)
			(unlocked yes)
			(layer "F.Fab")
			(hide yes)
			(effects
				(font
					(size 1 1)
					(thickness 0.15)
				)
			)
		)
		(property "Val" "5k11"
			(at 0 0 180)
			(unlocked yes)
			(layer "F.Fab")
			(hide yes)
			(effects
				(font
					(size 1 1)
					(thickness 0.15)
				)
			)
		)
		(property "License" "Apache-2.0"
			(at 0 0 180)
			(unlocked yes)
			(layer "F.Fab")
			(hide yes)
			(effects
				(font
					(size 1 1)
					(thickness 0.15)
				)
			)
		)
		(property "Author" "Antmicro"
			(at 0 0 180)
			(unlocked yes)
			(layer "F.Fab")
			(hide yes)
			(effects
				(font
					(size 1 1)
					(thickness 0.15)
				)
			)
		)
		(property "Tolerance" "1%"
			(at 0 0 180)
			(unlocked yes)
			(layer "F.Fab")
			(hide yes)
			(effects
				(font
					(size 1 1)
					(thickness 0.15)
				)
			)
		)
		(sheetname "/Debug FTDI + VNA/")
		(sheetfile "debug-ftdi.kicad_sch")
		(attr smd)
		(fp_rect
			(start -0.925 -0.47)
			(end 0.925 0.47)
			(stroke
				(width 0.05)
				(type default)
			)
			(fill no)
			(layer "F.CrtYd")
		)
		(fp_rect
			(start -0.5 -0.25)
			(end 0.5 0.25)
			(stroke
				(width 0.15)
				(type solid)
			)
			(fill no)
			(layer "F.Fab")
		)
		(fp_text user "Author: Antmicro"
			(at -0.95 4.169 180)
			(layer "F.Fab")
			(effects
				(font
					(size 0.7 0.7)
					(thickness 0.15)
				)
				(justify left bottom)
			)
		)
		(fp_text user "License: Apache-2.0"
			(at -0.95 5.169 180)
			(layer "F.Fab")
			(effects
				(font
					(size 0.7 0.7)
					(thickness 0.15)
				)
				(justify left bottom)
			)
		)
		(fp_text user "${REFERENCE}"
			(at -0.95 3.168 180)
			(layer "F.Fab")
			(effects
				(font
					(size 0.7 0.7)
					(thickness 0.15)
				)
				(justify left bottom)
			)
		)
		(pad "1" smd roundrect
			(at -0.48 0 180)
			(size 0.59 0.64)
			(layers "F.Cu" "F.Mask" "F.Paste")
			(roundrect_rratio 0.25)
			(net 1 "GND")
			(pintype "passive")
		)
		(pad "2" smd roundrect
			(at 0.48 0 180)
			(size 0.59 0.64)
			(layers "F.Cu" "F.Mask" "F.Paste")
			(roundrect_rratio 0.25)
			(net 363 "/Debug FTDI + VNA/CC1")
			(pintype "passive")
		)
	)
	(footprint "antmicro-footprints:VSSOP-8_2.3x2mm_P0.5mm"
		(layer "F.Cu")
		(at 247.257 185.507 180)
		(property "Reference" "U49"
			(at -0.218 1.433 0)
			(layer "F.SilkS")
			(effects
				(font
					(size 0.7 0.7)
					(thickness 0.15)
				)
				(justify right bottom)
			)
		)
		(property "Value" "TCA39306_VSSOP"
			(at 0 2.258 0)
			(layer "F.Fab")
			(effects
				(font
					(size 0.7 0.7)
					(thickness 0.15)
				)
				(justify right bottom)
			)
		)
		(property "Datasheet" "https://www.ti.com/lit/ds/symlink/tca39306.pdf?ts=1630428611843&ref_url=https%253A%252F%252Fwww.ti.com%252Fproduct%252FTCA39306"
			(at 0 0 180)
			(layer "F.Fab")
			(hide yes)
			(effects
				(font
					(size 1.27 1.27)
					(thickness 0.15)
				)
			)
		)
		(property "MPN" "TCA39306DCUR"
			(at 0 0 180)
			(unlocked yes)
			(layer "F.Fab")
			(hide yes)
			(effects
				(font
					(size 1 1)
					(thickness 0.15)
				)
			)
		)
		(property "Manufacturer" "Texas Instruments"
			(at 0 0 180)
			(unlocked yes)
			(layer "F.Fab")
			(hide yes)
			(effects
				(font
					(size 1 1)
					(thickness 0.15)
				)
			)
		)
		(property "Author" "Antmicro"
			(at 0 0 180)
			(unlocked yes)
			(layer "F.Fab")
			(hide yes)
			(effects
				(font
					(size 1 1)
					(thickness 0.15)
				)
			)
		)
		(property "License" "Apache-2.0"
			(at 0 0 180)
			(unlocked yes)
			(layer "F.Fab")
			(hide yes)
			(effects
				(font
					(size 1 1)
					(thickness 0.15)
				)
			)
		)
		(sheetname "/I^{2}C + I3C/")
		(sheetfile "i2c.kicad_sch")
		(attr smd)
		(fp_line
			(start 0.825 1.007)
			(end -0.82 1.007)
			(stroke
				(width 0.15)
				(type solid)
			)
			(layer "F.SilkS")
		)
		(fp_line
			(start -0.82 -0.992)
			(end 0.825 -0.992)
			(stroke
				(width 0.15)
				(type solid)
			)
			(layer "F.SilkS")
		)
		(fp_circle
			(center -1.402 -1.192)
			(end -1.352 -1.192)
			(stroke
				(width 0.15)
				(type solid)
			)
			(fill yes)
			(layer "F.SilkS")
		)
		(fp_rect
			(start 1.8 1.35)
			(end -1.8 -1.35)
			(stroke
				(width 0.05)
				(type solid)
			)
			(fill no)
			(layer "F.CrtYd")
		)
		(fp_line
			(start -0.7 -0.99)
			(end -1.14 -0.55)
			(stroke
				(width 0.15)
				(type solid)
			)
			(layer "F.Fab")
		)
		(fp_rect
			(start -1.147 -0.992)
			(end 1.151 1.007)
			(stroke
				(width 0.15)
				(type solid)
			)
			(fill no)
			(layer "F.Fab")
		)
		(fp_text user "License: Apache-2.0"
			(at -1.8 6.408 180)
			(layer "F.Fab")
			(effects
				(font
					(size 0.7 0.7)
					(thickness 0.15)
				)
				(justify left bottom)
			)
		)
		(fp_text user "${REFERENCE}"
			(at -1.8 4.006 180)
			(layer "F.Fab")
			(effects
				(font
					(size 0.7 0.7)
					(thickness 0.15)
				)
				(justify left bottom)
			)
		)
		(fp_text user "Author: Antmicro"
			(at -1.8 5.208 180)
			(layer "F.Fab")
			(effects
				(font
					(size 0.7 0.7)
					(thickness 0.15)
				)
				(justify left bottom)
			)
		)
		(pad "1" smd rect
			(at -1.372 -0.742 180)
			(size 0.75 0.4)
			(layers "F.Cu" "F.Mask" "F.Paste")
			(net 1 "GND")
			(pinfunction "GND")
			(pintype "power_in")
		)
		(pad "2" smd rect
			(at -1.372 -0.244 180)
			(size 0.75 0.3)
			(layers "F.Cu" "F.Mask" "F.Paste")
			(net 775 "Net-(Q24-S)")
			(pinfunction "Vref1")
			(pintype "power_in")
		)
		(pad "3" smd rect
			(at -1.372 0.256 180)
			(size 0.75 0.3)
			(layers "F.Cu" "F.Mask" "F.Paste")
			(net 369 "/I^{2}C + I3C/I3C_EXT.SCL")
			(pinfunction "SCL1")
			(pintype "bidirectional")
		)
		(pad "4" smd rect
			(at -1.372 0.757 180)
			(size 0.75 0.4)
			(layers "F.Cu" "F.Mask" "F.Paste")
			(net 368 "/I^{2}C + I3C/I3C_EXT.SDA")
			(pinfunction "SDA1")
			(pintype "bidirectional")
		)
		(pad "5" smd rect
			(at 1.377 0.757 180)
			(size 0.75 0.4)
			(layers "F.Cu" "F.Mask" "F.Paste")
			(net 528 "/FPGA banks HD/FPGA_I3C.SDA")
			(pinfunction "SDA2")
			(pintype "bidirectional")
		)
		(pad "6" smd rect
			(at 1.377 0.256 180)
			(size 0.75 0.3)
			(layers "F.Cu" "F.Mask" "F.Paste")
			(net 771 "/FPGA banks HD/FPGA_I3C.SCL")
			(pinfunction "SCL2")
			(pintype "bidirectional")
		)
		(pad "7" smd rect
			(at 1.377 -0.244 180)
			(size 0.75 0.3)
			(layers "F.Cu" "F.Mask" "F.Paste")
			(net 774 "Net-(U49-EN)")
			(pinfunction "Vref2")
			(pintype "power_in")
		)
		(pad "8" smd rect
			(at 1.377 -0.742 180)
			(size 0.75 0.4)
			(layers "F.Cu" "F.Mask" "F.Paste")
			(net 774 "Net-(U49-EN)")
			(pinfunction "EN")
			(pintype "input")
		)
	)
	(footprint "antmicro-footprints:C_0805_2012Metric"
		(layer "F.Cu")
		(at 219.325 185.8)
		(descr "Capacitor SMD 0805")
		(tags "capacitor SMD 0805")
		(property "Reference" "C21"
			(at -4.475001 0.470001 0)
			(layer "F.SilkS")
			(effects
				(font
					(size 0.7 0.7)
					(thickness 0.15)
				)
				(justify left bottom)
			)
		)
		(property "Value" "C_22u_25V_0805"
			(at -2.055717 1.963152 0)
			(layer "F.Fab")
			(effects
				(font
					(size 0.7 0.7)
					(thickness 0.15)
				)
				(justify left bottom)
			)
		)
		(property "Datasheet" "https://product.samsungsem.com/mlcc/CL21A226MAYNNN.do"
			(at 0 0 0)
			(layer "F.Fab")
			(hide yes)
			(effects
				(font
					(size 1.27 1.27)
					(thickness 0.15)
				)
			)
		)
		(property "MPN" "CL21A226MAYNNNE"
			(at 0 0 0)
			(unlocked yes)
			(layer "F.Fab")
			(hide yes)
			(effects
				(font
					(size 1 1)
					(thickness 0.15)
				)
			)
		)
		(property "Manufacturer" "Samsung Electro-Mechanics"
			(at 0 0 0)
			(unlocked yes)
			(layer "F.Fab")
			(hide yes)
			(effects
				(font
					(size 1 1)
					(thickness 0.15)
				)
			)
		)
		(property "License" "Apache-2.0"
			(at 0 0 0)
			(unlocked yes)
			(layer "F.Fab")
			(hide yes)
			(effects
				(font
					(size 1 1)
					(thickness 0.15)
				)
			)
		)
		(property "Author" "Antmicro"
			(at 0 0 0)
			(unlocked yes)
			(layer "F.Fab")
			(hide yes)
			(effects
				(font
					(size 1 1)
					(thickness 0.15)
				)
			)
		)
		(property "Val" "22u"
			(at 0 0 0)
			(unlocked yes)
			(layer "F.Fab")
			(hide yes)
			(effects
				(font
					(size 1 1)
					(thickness 0.15)
				)
			)
		)
		(property "Voltage" "25V"
			(at 0 0 0)
			(unlocked yes)
			(layer "F.Fab")
			(hide yes)
			(effects
				(font
					(size 1 1)
					(thickness 0.15)
				)
			)
		)
		(property "Dielectric" "X5R"
			(at 0 0 0)
			(unlocked yes)
			(layer "F.Fab")
			(hide yes)
			(effects
				(font
					(size 1 1)
					(thickness 0.15)
				)
			)
		)
		(property "Public" "False"
			(at 0 0 0)
			(unlocked yes)
			(layer "F.Fab")
			(hide yes)
			(effects
				(font
					(size 1 1)
					(thickness 0.15)
				)
			)
		)
		(sheetname "/Supply/DC-DC VCCINT/")
		(sheetfile "dc-dc-vccint.kicad_sch")
		(attr smd)
		(fp_line
			(start -0.3 -0.7)
			(end 0.3 -0.7)
			(stroke
				(width 0.15)
				(type solid)
			)
			(layer "F.SilkS")
		)
		(fp_line
			(start -0.3 0.7)
			(end 0.3 0.7)
			(stroke
				(width 0.15)
				(type solid)
			)
			(layer "F.SilkS")
		)
		(fp_rect
			(start 1.95 -0.9)
			(end -1.95 0.9)
			(stroke
				(width 0.05)
				(type default)
			)
			(fill no)
			(layer "F.CrtYd")
		)
		(fp_rect
			(start -0.95 -0.675)
			(end 0.95 0.675)
			(stroke
				(width 0.15)
				(type solid)
			)
			(fill no)
			(layer "F.Fab")
		)
		(fp_text user "${REFERENCE}"
			(at -1.9 3.947 0)
			(layer "F.Fab")
			(effects
				(font
					(size 0.7 0.7)
					(thickness 0.15)
				)
				(justify left bottom)
			)
		)
		(fp_text user "License: Apache-2.0"
			(at -1.9 4.947 0)
			(layer "F.Fab")
			(effects
				(font
					(size 0.7 0.7)
					(thickness 0.15)
				)
				(justify left bottom)
			)
		)
		(fp_text user "Author: Antmicro"
			(at -1.9 5.947 0)
			(layer "F.Fab")
			(effects
				(font
					(size 0.7 0.7)
					(thickness 0.15)
				)
				(justify left bottom)
			)
		)
		(pad "1" smd roundrect
			(at -1.1 0)
			(size 1.2 1.3)
			(layers "F.Cu" "F.Mask" "F.Paste")
			(roundrect_rratio 0.25)
			(net 1 "GND")
			(pintype "passive")
		)
		(pad "2" smd roundrect
			(at 1.1 0)
			(size 1.2 1.3)
			(layers "F.Cu" "F.Mask" "F.Paste")
			(roundrect_rratio 0.25)
			(net 35 "VDC")
			(pintype "passive")
		)
	)
)
